(kicad_pcb
	(version 20221018)
	(generator pcbnew)
	(general
    (thickness 1.518)
  )
	(paper "A4")
	(title_block
    (title "Kria K26 Devboard")
    (date "2024-03-26")
    (rev "1.2.5")
    (comment 1 "www.antmicro.com")
    (comment 2 "Antmicro Ltd.")
		(comment 9 "footprints 604-613 of 660")
	)
	(layers
    (0 "F.Cu" mixed)
    (1 "In1.Cu" power)
    (2 "In2.Cu" mixed)
    (3 "In3.Cu" power)
    (4 "In4.Cu" mixed)
    (5 "In5.Cu" power)
    (6 "In6.Cu" mixed)
    (31 "B.Cu" power)
    (32 "B.Adhes" user "B.Adhesive")
    (33 "F.Adhes" user "F.Adhesive")
    (34 "B.Paste" user)
    (35 "F.Paste" user)
    (36 "B.SilkS" user "B.Silkscreen")
    (37 "F.SilkS" user "F.Silkscreen")
    (38 "B.Mask" user)
    (39 "F.Mask" user)
    (40 "Dwgs.User" user "User.Drawings")
    (41 "Cmts.User" user "User.Comments")
    (42 "Eco1.User" user "User.Eco1")
    (43 "Eco2.User" user "User.Eco2")
    (44 "Edge.Cuts" user)
    (45 "Margin" user)
    (46 "B.CrtYd" user "B.Courtyard")
    (47 "F.CrtYd" user "F.Courtyard")
    (48 "B.Fab" user)
    (49 "F.Fab" user)
  )
	(footprint "kria-k26-devboard-footprints:C_0402_1005Metric" (layer "B.Cu")
    (at 108.95 88.55)
    (descr "Capacitor SMD 0402")
    (tags "capacitor SMD 0402")
    (property "Author" "Antmicro")
    (property "Dielectric" "X5R")
    (property "License" "Apache-2.0")
    (property "MPN" "GRM155R61H104KE14D")
    (property "Manufacturer" "Murata")
    (property "Sheetfile" "k26_som.kicad_sch")
    (property "Sheetname" "Xilinx K26 SOM")
    (property "Val" "100n")
    (property "Voltage" "50V")
    (property "ki_description" " ")
    (attr smd)
    (fp_text reference "C126" (at 3.68 1.56 180) (layer "B.SilkS")
        (effects (font (size 0.7 0.7) (thickness 0.15)) (justify left bottom mirror))
    )
    (fp_text value "C_100n_0402" (at 0 -1.4 180) (layer "B.Fab") hide
        (effects (font (size 0.7 0.7) (thickness 0.15)) (justify left bottom mirror))
    )
    (fp_text user "Author: Antmicro" (at -0.932 -4.17 180) (layer "B.Fab") hide
        (effects (font (size 0.7 0.7) (thickness 0.15)) (justify left bottom mirror))
    )
    (fp_text user "License: Apache-2.0" (at -0.932 -5.17 180) (layer "B.Fab") hide
        (effects (font (size 0.7 0.7) (thickness 0.15)) (justify left bottom mirror))
    )
    (fp_text user "${REFERENCE}" (at -0.932 -3.168 180) (layer "B.Fab") hide
        (effects (font (size 0.7 0.7) (thickness 0.15)) (justify left bottom mirror))
    )
    (fp_rect (start -0.94 0.47) (end 0.94 -0.47)
      (stroke (width 0.05) (type solid)) (fill none) (layer "B.CrtYd"))
    (fp_rect (start -0.499 0.249) (end 0.499 -0.249)
      (stroke (width 0.15) (type solid)) (fill none) (layer "B.Fab"))
    (pad "1" smd roundrect (at -0.484 0) (size 0.59 0.64) (layers "B.Cu" "B.Paste" "B.Mask") (roundrect_rratio 0.25)
      (net 243 "Net-(Q6-D)") (pintype "passive"))
    (pad "2" smd roundrect (at 0.484 0) (size 0.59 0.64) (layers "B.Cu" "B.Paste" "B.Mask") (roundrect_rratio 0.25)
      (net 1 "GND") (pintype "passive"))
  )
	(footprint "kria-k26-devboard-footprints:C_0402_1005Metric" (layer "B.Cu")
    (at 150.94 145.93)
    (descr "Capacitor SMD 0402")
    (tags "capacitor SMD 0402")
    (property "Author" "Antmicro")
    (property "Dielectric" "X5R")
    (property "License" "Apache-2.0")
    (property "MPN" "GRM155R61H104KE14D")
    (property "Manufacturer" "Murata")
    (property "Sheetfile" "kria-k26-devboard.kicad_sch")
    (property "Sheetname" "")
    (property "Val" "100n")
    (property "Voltage" "50V")
    (property "ki_description" " ")
    (attr smd)
    (fp_text reference "C1" (at 2.360711 0.312133 180) (layer "B.SilkS")
        (effects (font (size 0.7 0.7) (thickness 0.15)) (justify left bottom mirror))
    )
    (fp_text value "C_100n_0402" (at 0 -1.4 180) (layer "B.Fab") hide
        (effects (font (size 0.7 0.7) (thickness 0.15)) (justify left bottom mirror))
    )
    (fp_text user "Author: Antmicro" (at -0.932 -4.17 180) (layer "B.Fab") hide
        (effects (font (size 0.7 0.7) (thickness 0.15)) (justify left bottom mirror))
    )
    (fp_text user "License: Apache-2.0" (at -0.932 -5.17 180) (layer "B.Fab") hide
        (effects (font (size 0.7 0.7) (thickness 0.15)) (justify left bottom mirror))
    )
    (fp_text user "${REFERENCE}" (at -0.932 -3.168 180) (layer "B.Fab") hide
        (effects (font (size 0.7 0.7) (thickness 0.15)) (justify left bottom mirror))
    )
    (fp_rect (start -0.94 0.47) (end 0.94 -0.47)
      (stroke (width 0.05) (type solid)) (fill none) (layer "B.CrtYd"))
    (fp_rect (start -0.499 0.249) (end 0.499 -0.249)
      (stroke (width 0.15) (type solid)) (fill none) (layer "B.Fab"))
    (pad "1" smd roundrect (at -0.484 0) (size 0.59 0.64) (layers "B.Cu" "B.Paste" "B.Mask") (roundrect_rratio 0.25)
      (net 318 "SH_DOWN") (pintype "passive"))
    (pad "2" smd roundrect (at 0.484 0) (size 0.59 0.64) (layers "B.Cu" "B.Paste" "B.Mask") (roundrect_rratio 0.25)
      (net 1 "GND") (pintype "passive"))
  )
	(footprint "kria-k26-devboard-footprints:C_0402_1005Metric" (layer "B.Cu")
    (at 90.6 127.775 180)
    (descr "Capacitor SMD 0402")
    (tags "capacitor SMD 0402")
    (property "Author" "Antmicro")
    (property "Dielectric" "X5R")
    (property "License" "Apache-2.0")
    (property "MPN" "GRM155R61H104KE14D")
    (property "Manufacturer" "Murata")
    (property "Sheetfile" "k26_som.kicad_sch")
    (property "Sheetname" "Xilinx K26 SOM")
    (property "Val" "100n")
    (property "Voltage" "50V")
    (property "ki_description" " ")
    (attr smd)
    (fp_text reference "C128" (at 0.87 -0.355) (layer "B.SilkS")
        (effects (font (size 0.7 0.7) (thickness 0.15)) (justify left bottom mirror))
    )
    (fp_text value "C_100n_0402" (at 0 -1.4) (layer "B.Fab") hide
        (effects (font (size 0.7 0.7) (thickness 0.15)) (justify left bottom mirror))
    )
    (fp_text user "License: Apache-2.0" (at -0.932 -5.17) (layer "B.Fab") hide
        (effects (font (size 0.7 0.7) (thickness 0.15)) (justify left bottom mirror))
    )
    (fp_text user "Author: Antmicro" (at -0.932 -4.17) (layer "B.Fab") hide
        (effects (font (size 0.7 0.7) (thickness 0.15)) (justify left bottom mirror))
    )
    (fp_text user "${REFERENCE}" (at -0.932 -3.168) (layer "B.Fab") hide
        (effects (font (size 0.7 0.7) (thickness 0.15)) (justify left bottom mirror))
    )
    (fp_rect (start -0.94 0.47) (end 0.94 -0.47)
      (stroke (width 0.05) (type solid)) (fill none) (layer "B.CrtYd"))
    (fp_rect (start -0.499 0.249) (end 0.499 -0.249)
      (stroke (width 0.15) (type solid)) (fill none) (layer "B.Fab"))
    (pad "1" smd roundrect (at -0.484 0 180) (size 0.59 0.64) (layers "B.Cu" "B.Paste" "B.Mask") (roundrect_rratio 0.25)
      (net 20 "PL_3V3") (pintype "passive"))
    (pad "2" smd roundrect (at 0.484 0 180) (size 0.59 0.64) (layers "B.Cu" "B.Paste" "B.Mask") (roundrect_rratio 0.25)
      (net 1 "GND") (pintype "passive"))
  )
	(footprint "kria-k26-devboard-footprints:C_0402_1005Metric" (layer "B.Cu")
    (at 120.2 78.97 -90)
    (descr "Capacitor SMD 0402")
    (tags "capacitor SMD 0402")
    (property "Author" "Antmicro")
    (property "Dielectric" "X5R")
    (property "License" "Apache-2.0")
    (property "MPN" "GRM155R61H104KE14D")
    (property "Manufacturer" "Murata")
    (property "Sheetfile" "usb.kicad_sch")
    (property "Sheetname" "USB")
    (property "Val" "100n")
    (property "Voltage" "50V")
    (property "ki_description" " ")
    (attr smd)
    (fp_text reference "C50" (at -3.055 -0.28 90) (layer "B.SilkS")
        (effects (font (size 0.7 0.7) (thickness 0.15)) (justify left bottom mirror))
    )
    (fp_text value "C_100n_0402" (at 0 -1.4 90) (layer "B.Fab") hide
        (effects (font (size 0.7 0.7) (thickness 0.15)) (justify left bottom mirror))
    )
    (fp_text user "Author: Antmicro" (at -0.932 -4.17 90) (layer "B.Fab") hide
        (effects (font (size 0.7 0.7) (thickness 0.15)) (justify left bottom mirror))
    )
    (fp_text user "${REFERENCE}" (at -0.932 -3.168 90) (layer "B.Fab") hide
        (effects (font (size 0.7 0.7) (thickness 0.15)) (justify left bottom mirror))
    )
    (fp_text user "License: Apache-2.0" (at -0.932 -5.17 90) (layer "B.Fab") hide
        (effects (font (size 0.7 0.7) (thickness 0.15)) (justify left bottom mirror))
    )
    (fp_rect (start -0.94 0.47) (end 0.94 -0.47)
      (stroke (width 0.05) (type solid)) (fill none) (layer "B.CrtYd"))
    (fp_rect (start -0.499 0.249) (end 0.499 -0.249)
      (stroke (width 0.15) (type solid)) (fill none) (layer "B.Fab"))
    (pad "1" smd roundrect (at -0.484 0 270) (size 0.59 0.64) (layers "B.Cu" "B.Paste" "B.Mask") (roundrect_rratio 0.25)
      (net 15 "PS_3V3") (pintype "passive"))
    (pad "2" smd roundrect (at 0.484 0 270) (size 0.59 0.64) (layers "B.Cu" "B.Paste" "B.Mask") (roundrect_rratio 0.25)
      (net 1 "GND") (pintype "passive"))
  )
	(footprint "kria-k26-devboard-footprints:C_0603_1608Metric" (layer "B.Cu")
    (at 151.025 77.66)
    (descr "Capacitor SMD 0603")
    (tags "capacitor 0603")
    (property "Author" "Antmicro")
    (property "Dielectric" "")
    (property "License" "Apache-2.0")
    (property "MPN" "CL10A226MO7JZNC")
    (property "Manufacturer" "Samsung")
    (property "Sheetfile" "dc-dc-conventers.kicad_sch")
    (property "Sheetname" "DC/DC conventers")
    (property "Val" "22u/16V")
    (property "Voltage" "")
    (property "ki_description" " ")
    (attr smd)
    (fp_text reference "C195" (at 4.005 0.48 180) (layer "B.SilkS")
        (effects (font (size 0.7 0.7) (thickness 0.15)) (justify left bottom mirror))
    )
    (fp_text value "C_22u_16V_0603" (at 0 -1.6 180) (layer "B.Fab") hide
        (effects (font (size 0.7 0.7) (thickness 0.15)) (justify left bottom mirror))
    )
    (fp_text user "${REFERENCE}" (at -1.682 -3.895 180) (layer "B.Fab") hide
        (effects (font (size 0.7 0.7) (thickness 0.15)) (justify left bottom mirror))
    )
    (fp_text user "License: Apache-2.0" (at -1.682 -5.895 180) (layer "B.Fab") hide
        (effects (font (size 0.7 0.7) (thickness 0.15)) (justify left bottom mirror))
    )
    (fp_text user "Author: Antmicro" (at -1.682 -4.894 180) (layer "B.Fab") hide
        (effects (font (size 0.7 0.7) (thickness 0.15)) (justify left bottom mirror))
    )
    (fp_line (start -0.3 -0.3) (end 0.3 -0.3)
      (stroke (width 0.15) (type solid)) (layer "B.SilkS"))
    (fp_line (start -0.3 0.3) (end 0.3 0.3)
      (stroke (width 0.15) (type solid)) (layer "B.SilkS"))
    (fp_rect (start -1.24 0.7) (end 1.24 -0.7)
      (stroke (width 0.05) (type solid)) (fill none) (layer "B.CrtYd"))
    (fp_rect (start -0.8 0.4) (end 0.8 -0.4)
      (stroke (width 0.15) (type solid)) (fill none) (layer "B.Fab"))
    (pad "1" smd roundrect (at -0.7 0) (size 0.6 0.8) (layers "B.Cu" "B.Paste" "B.Mask") (roundrect_rratio 0.2)
      (net 772 "/Power Supply/DC/DC conventers/USB_5V_OUT") (pintype "passive"))
    (pad "2" smd roundrect (at 0.7 0) (size 0.6 0.8) (layers "B.Cu" "B.Paste" "B.Mask") (roundrect_rratio 0.2)
      (net 1 "GND") (pintype "passive"))
  )
	(footprint "kria-k26-devboard-footprints:R_0402_1005Metric" (layer "B.Cu")
    (at 146.559999 76.14 -90)
    (descr "Resistor SMD 0402")
    (tags "resistor SMD 0402")
    (property "Author" "Antmicro")
    (property "License" "Apache-2.0")
    (property "MPN" "CR0402-FX-2402GLF")
    (property "Manufacturer" "Bourns")
    (property "Sheetfile" "dc-dc-conventers.kicad_sch")
    (property "Sheetname" "DC/DC conventers")
    (property "Tolerance" "1%")
    (property "Val" "24k")
    (property "ki_description" "24k resistor in 0402 package with 1% tolerance")
    (attr smd)
    (fp_text reference "R123" (at -1.494239 2.543351 90) (layer "B.SilkS")
        (effects (font (size 0.7 0.7) (thickness 0.15)) (justify left bottom mirror))
    )
    (fp_text value "R_24k_0402" (at 0 -1.4 90) (layer "B.Fab") hide
        (effects (font (size 0.7 0.7) (thickness 0.15)) (justify left bottom mirror))
    )
    (fp_text user "Author: Antmicro" (at -0.95 -4.169 90) (layer "B.Fab") hide
        (effects (font (size 0.7 0.7) (thickness 0.15)) (justify left bottom mirror))
    )
    (fp_text user "${REFERENCE}" (at -0.95 -3.168 90) (layer "B.Fab") hide
        (effects (font (size 0.7 0.7) (thickness 0.15)) (justify left bottom mirror))
    )
    (fp_text user "License: Apache-2.0" (at -0.95 -5.169 90) (layer "B.Fab") hide
        (effects (font (size 0.7 0.7) (thickness 0.15)) (justify left bottom mirror))
    )
    (fp_rect (start -0.93 0.47) (end 0.93 -0.47)
      (stroke (width 0.05) (type solid)) (fill none) (layer "B.CrtYd"))
    (fp_rect (start -0.5 0.25) (end 0.5 -0.25)
      (stroke (width 0.15) (type solid)) (fill none) (layer "B.Fab"))
    (pad "1" smd roundrect (at -0.485 0 270) (size 0.59 0.64) (layers "B.Cu" "B.Paste" "B.Mask") (roundrect_rratio 0.25)
      (net 254 "Net-(U47-FB)") (pintype "passive"))
    (pad "2" smd roundrect (at 0.485 0 270) (size 0.59 0.64) (layers "B.Cu" "B.Paste" "B.Mask") (roundrect_rratio 0.25)
      (net 1 "GND") (pintype "passive"))
  )
	(footprint "kria-k26-devboard-footprints:C_0402_1005Metric" (layer "B.Cu")
    (at 95.49 84.96 90)
    (descr "Capacitor SMD 0402")
    (tags "capacitor SMD 0402")
    (property "Author" "Antmicro")
    (property "Dielectric" "X5R")
    (property "License" "Apache-2.0")
    (property "MPN" "GRM155R61H104KE14D")
    (property "Manufacturer" "Murata")
    (property "Sheetfile" "dp.kicad_sch")
    (property "Sheetname" "Display Port")
    (property "Val" "100n")
    (property "Voltage" "50V")
    (property "ki_description" " ")
    (attr smd)
    (fp_text reference "C4" (at 0.88 1.38 270) (layer "B.SilkS")
        (effects (font (size 0.7 0.7) (thickness 0.15)) (justify left bottom mirror))
    )
    (fp_text value "C_100n_0402" (at 0 -1.4 270) (layer "B.Fab") hide
        (effects (font (size 0.7 0.7) (thickness 0.15)) (justify left bottom mirror))
    )
    (fp_text user "License: Apache-2.0" (at -0.932 -5.17 270) (layer "B.Fab") hide
        (effects (font (size 0.7 0.7) (thickness 0.15)) (justify left bottom mirror))
    )
    (fp_text user "${REFERENCE}" (at -0.932 -3.168 270) (layer "B.Fab") hide
        (effects (font (size 0.7 0.7) (thickness 0.15)) (justify left bottom mirror))
    )
    (fp_text user "Author: Antmicro" (at -0.932 -4.17 270) (layer "B.Fab") hide
        (effects (font (size 0.7 0.7) (thickness 0.15)) (justify left bottom mirror))
    )
    (fp_rect (start -0.94 0.47) (end 0.94 -0.47)
      (stroke (width 0.05) (type solid)) (fill none) (layer "B.CrtYd"))
    (fp_rect (start -0.499 0.249) (end 0.499 -0.249)
      (stroke (width 0.15) (type solid)) (fill none) (layer "B.Fab"))
    (pad "1" smd roundrect (at -0.484 0 90) (size 0.59 0.64) (layers "B.Cu" "B.Paste" "B.Mask") (roundrect_rratio 0.25)
      (net 15 "PS_3V3") (pintype "passive"))
    (pad "2" smd roundrect (at 0.484 0 90) (size 0.59 0.64) (layers "B.Cu" "B.Paste" "B.Mask") (roundrect_rratio 0.25)
      (net 1 "GND") (pintype "passive"))
  )
	(footprint "kria-k26-devboard-footprints:C_0402_1005Metric" (layer "B.Cu")
    (at 118.9 90.35 90)
    (descr "Capacitor SMD 0402")
    (tags "capacitor SMD 0402")
    (property "Author" "Antmicro")
    (property "Dielectric" "X5R")
    (property "License" "Apache-2.0")
    (property "MPN" "GRM155R61H104KE14D")
    (property "Manufacturer" "Murata")
    (property "Sheetfile" "usb.kicad_sch")
    (property "Sheetname" "USB")
    (property "Val" "100n")
    (property "Voltage" "50V")
    (property "ki_description" " ")
    (attr smd)
    (fp_text reference "C47" (at 0.5 -1.52 270) (layer "B.SilkS")
        (effects (font (size 0.7 0.7) (thickness 0.15)) (justify left bottom mirror))
    )
    (fp_text value "C_100n_0402" (at 0 -1.4 270) (layer "B.Fab") hide
        (effects (font (size 0.7 0.7) (thickness 0.15)) (justify left bottom mirror))
    )
    (fp_text user "Author: Antmicro" (at -0.932 -4.17 270) (layer "B.Fab") hide
        (effects (font (size 0.7 0.7) (thickness 0.15)) (justify left bottom mirror))
    )
    (fp_text user "License: Apache-2.0" (at -0.932 -5.17 270) (layer "B.Fab") hide
        (effects (font (size 0.7 0.7) (thickness 0.15)) (justify left bottom mirror))
    )
    (fp_text user "${REFERENCE}" (at -0.932 -3.168 270) (layer "B.Fab") hide
        (effects (font (size 0.7 0.7) (thickness 0.15)) (justify left bottom mirror))
    )
    (fp_rect (start -0.94 0.47) (end 0.94 -0.47)
      (stroke (width 0.05) (type solid)) (fill none) (layer "B.CrtYd"))
    (fp_rect (start -0.499 0.249) (end 0.499 -0.249)
      (stroke (width 0.15) (type solid)) (fill none) (layer "B.Fab"))
    (pad "1" smd roundrect (at -0.484 0 90) (size 0.59 0.64) (layers "B.Cu" "B.Paste" "B.Mask") (roundrect_rratio 0.25)
      (net 15 "PS_3V3") (pintype "passive"))
    (pad "2" smd roundrect (at 0.484 0 90) (size 0.59 0.64) (layers "B.Cu" "B.Paste" "B.Mask") (roundrect_rratio 0.25)
      (net 1 "GND") (pintype "passive"))
  )
	(footprint "kria-k26-devboard-footprints:C_0402_1005Metric" (layer "B.Cu")
    (at 116.656942 81.5)
    (descr "Capacitor SMD 0402")
    (tags "capacitor SMD 0402")
    (property "Author" "Antmicro")
    (property "Dielectric" "X5R")
    (property "License" "Apache-2.0")
    (property "MPN" "GRM155R61H104KE14D")
    (property "Manufacturer" "Murata")
    (property "Sheetfile" "usb.kicad_sch")
    (property "Sheetname" "USB")
    (property "Val" "100n")
    (property "Voltage" "50V")
    (property "ki_description" " ")
    (attr smd)
    (fp_text reference "C45" (at -0.916942 0.43 180) (layer "B.SilkS")
        (effects (font (size 0.7 0.7) (thickness 0.15)) (justify left bottom mirror))
    )
    (fp_text value "C_100n_0402" (at 0 -1.4 180) (layer "B.Fab") hide
        (effects (font (size 0.7 0.7) (thickness 0.15)) (justify left bottom mirror))
    )
    (fp_text user "${REFERENCE}" (at -0.932 -3.168 180) (layer "B.Fab") hide
        (effects (font (size 0.7 0.7) (thickness 0.15)) (justify left bottom mirror))
    )
    (fp_text user "License: Apache-2.0" (at -0.932 -5.17 180) (layer "B.Fab") hide
        (effects (font (size 0.7 0.7) (thickness 0.15)) (justify left bottom mirror))
    )
    (fp_text user "Author: Antmicro" (at -0.932 -4.17 180) (layer "B.Fab") hide
        (effects (font (size 0.7 0.7) (thickness 0.15)) (justify left bottom mirror))
    )
    (fp_rect (start -0.94 0.47) (end 0.94 -0.47)
      (stroke (width 0.05) (type solid)) (fill none) (layer "B.CrtYd"))
    (fp_rect (start -0.499 0.249) (end 0.499 -0.249)
      (stroke (width 0.15) (type solid)) (fill none) (layer "B.Fab"))
    (pad "1" smd roundrect (at -0.484 0) (size 0.59 0.64) (layers "B.Cu" "B.Paste" "B.Mask") (roundrect_rratio 0.25)
      (net 18 "PS_1V2") (pintype "passive"))
    (pad "2" smd roundrect (at 0.484 0) (size 0.59 0.64) (layers "B.Cu" "B.Paste" "B.Mask") (roundrect_rratio 0.25)
      (net 1 "GND") (pintype "passive"))
  )
	(footprint "kria-k26-devboard-footprints:R_0402_1005Metric" (layer "B.Cu")
    (at 116.2 78.97 90)
    (descr "Resistor SMD 0402")
    (tags "resistor SMD 0402")
    (property "Author" "Antmicro")
    (property "License" "Apache-2.0")
    (property "MPN" "CR0402-FX-2003GLF")
    (property "Manufacturer" "Bourns")
    (property "Sheetfile" "usb.kicad_sch")
    (property "Sheetname" "USB")
    (property "Tolerance" "1%")
    (property "Val" "200k")
    (property "ki_description" "200k resistor in 0402 package with 1% tolerance")
    (attr smd)
    (fp_text reference "R59" (at 3.065 0.38 270) (layer "B.SilkS")
        (effects (font (size 0.7 0.7) (thickness 0.15)) (justify left bottom mirror))
    )
    (fp_text value "R_200k_0402" (at 0 -1.4 270) (layer "B.Fab") hide
        (effects (font (size 0.7 0.7) (thickness 0.15)) (justify left bottom mirror))
    )
    (fp_text user "${REFERENCE}" (at -0.95 -3.168 270) (layer "B.Fab") hide
        (effects (font (size 0.7 0.7) (thickness 0.15)) (justify left bottom mirror))
    )
    (fp_text user "Author: Antmicro" (at -0.95 -4.169 270) (layer "B.Fab") hide
        (effects (font (size 0.7 0.7) (thickness 0.15)) (justify left bottom mirror))
    )
    (fp_text user "License: Apache-2.0" (at -0.95 -5.169 270) (layer "B.Fab") hide
        (effects (font (size 0.7 0.7) (thickness 0.15)) (justify left bottom mirror))
    )
    (fp_rect (start -0.93 0.47) (end 0.93 -0.47)
      (stroke (width 0.05) (type solid)) (fill none) (layer "B.CrtYd"))
    (fp_rect (start -0.5 0.25) (end 0.5 -0.25)
      (stroke (width 0.15) (type solid)) (fill none) (layer "B.Fab"))
    (pad "1" smd roundrect (at -0.485 0 90) (size 0.59 0.64) (layers "B.Cu" "B.Paste" "B.Mask") (roundrect_rratio 0.25)
      (net 1 "GND") (pintype "passive"))
    (pad "2" smd roundrect (at 0.485 0 90) (size 0.59 0.64) (layers "B.Cu" "B.Paste" "B.Mask") (roundrect_rratio 0.25)
      (net 662 "Net-(U17-PF9)") (pintype "passive"))
  )
)
